(kicad_pcb
	(version 20260206)
	(generator "pcbnew")
	(generator_version "10.0")
	(general
		(thickness 1.6)
		(legacy_teardrops no)
	)
	(paper "A4")
	(title_block
		(title "peb — Lightning_PEB_BRD.brd")
		(comment 1 "Lightning (Wiwynn / Facebook NVMe JBOF) / footprints 892-898 of 2563")
	)
	(layers
		(0 "F.Cu" signal "TOP")
		(4 "In1.Cu" signal "L2GND")
		(6 "In2.Cu" signal "L3")
		(8 "In3.Cu" signal "L4VCC")
		(10 "In4.Cu" signal "L5VCC")
		(12 "In5.Cu" signal "L6")
		(14 "In6.Cu" signal "L7GND")
		(2 "B.Cu" signal "BOTTOM")
		(9 "F.Adhes" user "F.Adhesive")
		(11 "B.Adhes" user "B.Adhesive")
		(13 "F.Paste" user "Package Geometry/Pastemask Top")
		(15 "B.Paste" user "Package Geometry/Pastemask Bottom")
		(5 "F.SilkS" user "Ref Des/Silkscreen Top")
		(7 "B.SilkS" user "Ref Des/Silkscreen Bottom")
		(1 "F.Mask" user "Board Geometry/Soldermask Top")
		(3 "B.Mask" user "Board Geometry/Soldermask Bottom")
		(17 "Dwgs.User" user "User.Drawings")
		(19 "Cmts.User" user "User.Comments")
		(21 "Eco1.User" user "User.Eco1")
		(23 "Eco2.User" user "User.Eco2")
		(25 "Edge.Cuts" user "Board Geometry/Outline")
		(27 "Margin" user)
		(31 "F.CrtYd" user "Package Geometry/Place Bound Top")
		(29 "B.CrtYd" user "Package Geometry/Place Bound Bottom")
		(35 "F.Fab" user "Ref Des/Assembly Top")
		(33 "B.Fab" user "Ref Des/Assembly Bottom")
	)
	(footprint ""
		(layer "F.Cu")
		(at 333.788512 -172.432218)
		(property "Reference" "R7936"
			(at 0 0 0)
			(layer "F.SilkS")
			(hide yes)
			(effects
				(font
					(size 1.27 1.27)
				)
			)
		)
		(property "Value" "0R2J-2-GP"
			(at 0.064008 -3.993896 0)
			(unlocked yes)
			(layer "F.Fab")
			(hide yes)
			(effects
				(font
					(size 1.016 1.016)
					(thickness 0.1524)
				)
			)
		)
		(property "Device Type" "R402H16"
			(at 0.064008 -5.517896 0)
			(unlocked yes)
			(layer "F.Fab")
			(hide yes)
			(effects
				(font
					(size 1.016 1.016)
					(thickness 0.1524)
				)
			)
		)
		(duplicate_pad_numbers_are_jumpers no)
		(fp_line
			(start -0.508 -0.9398)
			(end -0.508 0.9398)
			(stroke
				(width 0.1524)
				(type default)
			)
			(layer "F.SilkS")
		)
		(fp_line
			(start 0.508 -0.9398)
			(end -0.508 -0.9398)
			(stroke
				(width 0.1524)
				(type default)
			)
			(layer "F.SilkS")
		)
		(fp_rect
			(start -0.508 0.9398)
			(end 0.508 -0.9398)
			(stroke
				(width 0)
				(type default)
			)
			(fill no)
			(layer "F.CrtYd")
		)
		(fp_rect
			(start -0.508 0.9398)
			(end 0.508 -0.9398)
			(stroke
				(width 0)
				(type default)
			)
			(fill no)
			(layer "F.Fab")
		)
		(pad "1" smd custom
			(at 0 -0.4445)
			(size 0.1397 0.1397)
			(layers "F.Cu" "F.Mask" "F.Paste")
			(net "SSD_ATNLED#4")
			(options
				(clearance outline)
				(anchor circle)
			)
			(primitives
				(gr_poly
					(pts
						(arc
							(start -0.1778 -0.2794)
							(mid -0.249642 -0.249642)
							(end -0.2794 -0.1778)
						)
						(arc
							(start -0.2794 0.1778)
							(mid -0.249642 0.249642)
							(end -0.1778 0.2794)
						)
						(arc
							(start 0.1778 0.2794)
							(mid 0.249642 0.249642)
							(end 0.2794 0.1778)
						)
						(arc
							(start 0.2794 -0.1778)
							(mid 0.249642 -0.249642)
							(end 0.1778 -0.2794)
						)
					)
					(width 0)
					(fill yes)
				)
			)
		)
		(pad "2" smd custom
			(at 0 0.4445)
			(size 0.1397 0.1397)
			(layers "F.Cu" "F.Mask" "F.Paste")
			(net "SSD_ATNLED#4_R")
			(options
				(clearance outline)
				(anchor circle)
			)
			(primitives
				(gr_poly
					(pts
						(arc
							(start -0.1778 -0.2794)
							(mid -0.249642 -0.249642)
							(end -0.2794 -0.1778)
						)
						(arc
							(start -0.2794 0.1778)
							(mid -0.249642 0.249642)
							(end -0.1778 0.2794)
						)
						(arc
							(start 0.1778 0.2794)
							(mid 0.249642 0.249642)
							(end 0.2794 0.1778)
						)
						(arc
							(start 0.2794 -0.1778)
							(mid 0.249642 -0.249642)
							(end 0.1778 -0.2794)
						)
					)
					(width 0)
					(fill yes)
				)
			)
		)
	)
	(footprint ""
		(layer "F.Cu")
		(at 149.352 -33.528)
		(property "Reference" "C393"
			(at 0 0 0)
			(layer "F.SilkS")
			(hide yes)
			(effects
				(font
					(size 1.27 1.27)
				)
			)
		)
		(property "Value" "SCD22U10V2KX-1GP"
			(at 1.1811 -2.7051 0)
			(unlocked yes)
			(layer "F.Fab")
			(hide yes)
			(effects
				(font
					(size 1.016 1.016)
					(thickness 0.1524)
				)
			)
		)
		(property "Device Type" "C402H22"
			(at 1.1811 -4.2291 0)
			(unlocked yes)
			(layer "F.Fab")
			(hide yes)
			(effects
				(font
					(size 1.016 1.016)
					(thickness 0.1524)
				)
			)
		)
		(duplicate_pad_numbers_are_jumpers no)
		(fp_rect
			(start -0.4318 0.9525)
			(end 0.4318 -0.9525)
			(stroke
				(width 0)
				(type default)
			)
			(fill no)
			(layer "F.CrtYd")
		)
		(fp_rect
			(start -0.4318 0.9525)
			(end 0.4318 -0.9525)
			(stroke
				(width 0)
				(type default)
			)
			(fill no)
			(layer "F.Fab")
		)
		(pad "1" smd custom
			(at 0 -0.4445)
			(size 0.1524 0.1524)
			(layers "F.Cu" "F.Mask" "F.Paste")
			(net "PCIE_TX_CAP_N86")
			(options
				(clearance outline)
				(anchor circle)
			)
			(primitives
				(gr_poly
					(pts
						(arc
							(start 0.3048 -0.2032)
							(mid 0.275042 -0.275042)
							(end 0.2032 -0.3048)
						)
						(arc
							(start -0.2032 -0.3048)
							(mid -0.275042 -0.275042)
							(end -0.3048 -0.2032)
						)
						(arc
							(start -0.3048 0.2032)
							(mid -0.275042 0.275042)
							(end -0.2032 0.3048)
						)
						(arc
							(start 0.2032 0.3048)
							(mid 0.275042 0.275042)
							(end 0.3048 0.2032)
						)
					)
					(width 0)
					(fill yes)
				)
			)
		)
		(pad "2" smd custom
			(at 0 0.4445)
			(size 0.1524 0.1524)
			(layers "F.Cu" "F.Mask" "F.Paste")
			(net "PCIE_TX_N86")
			(options
				(clearance outline)
				(anchor circle)
			)
			(primitives
				(gr_poly
					(pts
						(arc
							(start 0.3048 -0.2032)
							(mid 0.275042 -0.275042)
							(end 0.2032 -0.3048)
						)
						(arc
							(start -0.2032 -0.3048)
							(mid -0.275042 -0.275042)
							(end -0.3048 -0.2032)
						)
						(arc
							(start -0.3048 0.2032)
							(mid -0.275042 0.275042)
							(end -0.2032 0.3048)
						)
						(arc
							(start 0.2032 0.3048)
							(mid 0.275042 0.275042)
							(end 0.3048 0.2032)
						)
					)
					(width 0)
					(fill yes)
				)
			)
		)
	)
	(footprint ""
		(layer "F.Cu")
		(at 53.721 -128.524 90)
		(property "Reference" "R452"
			(at 0 0 90)
			(layer "F.SilkS")
			(hide yes)
			(effects
				(font
					(size 1.27 1.27)
				)
			)
		)
		(property "Value" "0R2J-2-GP"
			(at 0.064008 -3.993896 90)
			(unlocked yes)
			(layer "F.Fab")
			(hide yes)
			(effects
				(font
					(size 1.016 1.016)
					(thickness 0.1524)
				)
			)
		)
		(property "Device Type" "R402H16"
			(at 0.064008 -5.517896 90)
			(unlocked yes)
			(layer "F.Fab")
			(hide yes)
			(effects
				(font
					(size 1.016 1.016)
					(thickness 0.1524)
				)
			)
		)
		(duplicate_pad_numbers_are_jumpers no)
		(fp_line
			(start 0.508 -0.9398)
			(end -0.508 -0.9398)
			(stroke
				(width 0.1524)
				(type default)
			)
			(layer "F.SilkS")
		)
		(fp_line
			(start -0.508 -0.9398)
			(end -0.508 0.9398)
			(stroke
				(width 0.1524)
				(type default)
			)
			(layer "F.SilkS")
		)
		(fp_rect
			(start -0.508 0.9398)
			(end 0.508 -0.9398)
			(stroke
				(width 0)
				(type default)
			)
			(fill no)
			(layer "F.CrtYd")
		)
		(fp_rect
			(start -0.508 0.9398)
			(end 0.508 -0.9398)
			(stroke
				(width 0)
				(type default)
			)
			(fill no)
			(layer "F.Fab")
		)
		(pad "1" smd custom
			(at 0 -0.4445 90)
			(size 0.1397 0.1397)
			(layers "F.Cu" "F.Mask" "F.Paste")
			(net "BMC_USB1_HDN")
			(options
				(clearance outline)
				(anchor circle)
			)
			(primitives
				(gr_poly
					(pts
						(arc
							(start -0.1778 -0.2794)
							(mid -0.249642 -0.249642)
							(end -0.2794 -0.1778)
						)
						(arc
							(start -0.2794 0.1778)
							(mid -0.249642 0.249642)
							(end -0.1778 0.2794)
						)
						(arc
							(start 0.1778 0.2794)
							(mid 0.249642 0.249642)
							(end 0.2794 0.1778)
						)
						(arc
							(start 0.2794 -0.1778)
							(mid 0.249642 -0.249642)
							(end 0.1778 -0.2794)
						)
					)
					(width 0)
					(fill yes)
				)
			)
		)
		(pad "2" smd custom
			(at 0 0.4445 90)
			(size 0.1397 0.1397)
			(layers "F.Cu" "F.Mask" "F.Paste")
			(net "USB_P2_DN")
			(options
				(clearance outline)
				(anchor circle)
			)
			(primitives
				(gr_poly
					(pts
						(arc
							(start -0.1778 -0.2794)
							(mid -0.249642 -0.249642)
							(end -0.2794 -0.1778)
						)
						(arc
							(start -0.2794 0.1778)
							(mid -0.249642 0.249642)
							(end -0.1778 0.2794)
						)
						(arc
							(start 0.1778 0.2794)
							(mid 0.249642 0.249642)
							(end 0.2794 0.1778)
						)
						(arc
							(start 0.2794 -0.1778)
							(mid 0.249642 -0.249642)
							(end 0.1778 -0.2794)
						)
					)
					(width 0)
					(fill yes)
				)
			)
		)
	)
	(footprint ""
		(layer "F.Cu")
		(at 333.19974 -36.90874 90)
		(property "Reference" "R625"
			(at 0 0 90)
			(layer "F.SilkS")
			(hide yes)
			(effects
				(font
					(size 1.27 1.27)
				)
			)
		)
		(property "Value" "0R2J-2-GP"
			(at 0.064008 -3.993896 90)
			(unlocked yes)
			(layer "F.Fab")
			(hide yes)
			(effects
				(font
					(size 1.016 1.016)
					(thickness 0.1524)
				)
			)
		)
		(property "Device Type" "R402H16"
			(at 0.064008 -5.517896 90)
			(unlocked yes)
			(layer "F.Fab")
			(hide yes)
			(effects
				(font
					(size 1.016 1.016)
					(thickness 0.1524)
				)
			)
		)
		(duplicate_pad_numbers_are_jumpers no)
		(fp_line
			(start 0.508 -0.9398)
			(end -0.508 -0.9398)
			(stroke
				(width 0.1524)
				(type default)
			)
			(layer "F.SilkS")
		)
		(fp_line
			(start -0.508 -0.9398)
			(end -0.508 0.9398)
			(stroke
				(width 0.1524)
				(type default)
			)
			(layer "F.SilkS")
		)
		(fp_rect
			(start -0.508 0.9398)
			(end 0.508 -0.9398)
			(stroke
				(width 0)
				(type default)
			)
			(fill no)
			(layer "F.CrtYd")
		)
		(fp_rect
			(start -0.508 0.9398)
			(end 0.508 -0.9398)
			(stroke
				(width 0)
				(type default)
			)
			(fill no)
			(layer "F.Fab")
		)
		(pad "1" smd custom
			(at 0 -0.4445 90)
			(size 0.1397 0.1397)
			(layers "F.Cu" "F.Mask" "F.Paste")
			(net "UPLINK6_R")
			(options
				(clearance outline)
				(anchor circle)
			)
			(primitives
				(gr_poly
					(pts
						(arc
							(start -0.1778 -0.2794)
							(mid -0.249642 -0.249642)
							(end -0.2794 -0.1778)
						)
						(arc
							(start -0.2794 0.1778)
							(mid -0.249642 0.249642)
							(end -0.1778 0.2794)
						)
						(arc
							(start 0.1778 0.2794)
							(mid 0.249642 0.249642)
							(end 0.2794 0.1778)
						)
						(arc
							(start 0.2794 -0.1778)
							(mid 0.249642 -0.249642)
							(end 0.1778 -0.2794)
						)
					)
					(width 0)
					(fill yes)
				)
			)
		)
		(pad "2" smd custom
			(at 0 0.4445 90)
			(size 0.1397 0.1397)
			(layers "F.Cu" "F.Mask" "F.Paste")
			(net "UPLINK6")
			(options
				(clearance outline)
				(anchor circle)
			)
			(primitives
				(gr_poly
					(pts
						(arc
							(start -0.1778 -0.2794)
							(mid -0.249642 -0.249642)
							(end -0.2794 -0.1778)
						)
						(arc
							(start -0.2794 0.1778)
							(mid -0.249642 0.249642)
							(end -0.1778 0.2794)
						)
						(arc
							(start 0.1778 0.2794)
							(mid 0.249642 0.249642)
							(end 0.2794 0.1778)
						)
						(arc
							(start 0.2794 -0.1778)
							(mid 0.249642 -0.249642)
							(end 0.1778 -0.2794)
						)
					)
					(width 0)
					(fill yes)
				)
			)
		)
	)
	(footprint ""
		(layer "F.Cu")
		(at 340.9442 -172.339)
		(property "Reference" "R9038"
			(at 0 0 0)
			(layer "F.SilkS")
			(hide yes)
			(effects
				(font
					(size 1.27 1.27)
				)
			)
		)
		(property "Value" "4K7R2F-GP"
			(at 0.064008 -3.993896 0)
			(unlocked yes)
			(layer "F.Fab")
			(hide yes)
			(effects
				(font
					(size 1.016 1.016)
					(thickness 0.1524)
				)
			)
		)
		(property "Device Type" "R402H16"
			(at 0.064008 -5.517896 0)
			(unlocked yes)
			(layer "F.Fab")
			(hide yes)
			(effects
				(font
					(size 1.016 1.016)
					(thickness 0.1524)
				)
			)
		)
		(duplicate_pad_numbers_are_jumpers no)
		(fp_line
			(start -0.508 -0.9398)
			(end -0.508 0.9398)
			(stroke
				(width 0.1524)
				(type default)
			)
			(layer "F.SilkS")
		)
		(fp_line
			(start 0.508 -0.9398)
			(end -0.508 -0.9398)
			(stroke
				(width 0.1524)
				(type default)
			)
			(layer "F.SilkS")
		)
		(fp_rect
			(start -0.508 0.9398)
			(end 0.508 -0.9398)
			(stroke
				(width 0)
				(type default)
			)
			(fill no)
			(layer "F.CrtYd")
		)
		(fp_rect
			(start -0.508 0.9398)
			(end 0.508 -0.9398)
			(stroke
				(width 0)
				(type default)
			)
			(fill no)
			(layer "F.Fab")
		)
		(pad "1" smd custom
			(at 0 -0.4445)
			(size 0.1397 0.1397)
			(layers "F.Cu" "F.Mask" "F.Paste")
			(net "SSD_PERST#9")
			(options
				(clearance outline)
				(anchor circle)
			)
			(primitives
				(gr_poly
					(pts
						(arc
							(start -0.1778 -0.2794)
							(mid -0.249642 -0.249642)
							(end -0.2794 -0.1778)
						)
						(arc
							(start -0.2794 0.1778)
							(mid -0.249642 0.249642)
							(end -0.1778 0.2794)
						)
						(arc
							(start 0.1778 0.2794)
							(mid 0.249642 0.249642)
							(end 0.2794 0.1778)
						)
						(arc
							(start 0.2794 -0.1778)
							(mid 0.249642 -0.249642)
							(end 0.1778 -0.2794)
						)
					)
					(width 0)
					(fill yes)
				)
			)
		)
		(pad "2" smd custom
			(at 0 0.4445)
			(size 0.1397 0.1397)
			(layers "F.Cu" "F.Mask" "F.Paste")
			(net "GND")
			(options
				(clearance outline)
				(anchor circle)
			)
			(primitives
				(gr_poly
					(pts
						(arc
							(start -0.1778 -0.2794)
							(mid -0.249642 -0.249642)
							(end -0.2794 -0.1778)
						)
						(arc
							(start -0.2794 0.1778)
							(mid -0.249642 0.249642)
							(end -0.1778 0.2794)
						)
						(arc
							(start 0.1778 0.2794)
							(mid 0.249642 0.249642)
							(end 0.2794 0.1778)
						)
						(arc
							(start 0.2794 -0.1778)
							(mid 0.249642 -0.249642)
							(end 0.1778 -0.2794)
						)
					)
					(width 0)
					(fill yes)
				)
			)
		)
	)
	(footprint ""
		(layer "F.Cu")
		(at 59.81827 -37.175948)
		(property "Reference" "PR32"
			(at 0 0 0)
			(layer "F.SilkS")
			(hide yes)
			(effects
				(font
					(size 1.27 1.27)
				)
			)
		)
		(property "Value" "866KR2F-GP"
			(at 0.064008 -3.993896 0)
			(unlocked yes)
			(layer "F.Fab")
			(hide yes)
			(effects
				(font
					(size 1.016 1.016)
					(thickness 0.1524)
				)
			)
		)
		(property "Device Type" "R402H16"
			(at 0.064008 -5.517896 0)
			(unlocked yes)
			(layer "F.Fab")
			(hide yes)
			(effects
				(font
					(size 1.016 1.016)
					(thickness 0.1524)
				)
			)
		)
		(duplicate_pad_numbers_are_jumpers no)
		(fp_line
			(start -0.508 -0.9398)
			(end -0.508 0.9398)
			(stroke
				(width 0.1524)
				(type default)
			)
			(layer "F.SilkS")
		)
		(fp_line
			(start 0.508 -0.9398)
			(end -0.508 -0.9398)
			(stroke
				(width 0.1524)
				(type default)
			)
			(layer "F.SilkS")
		)
		(fp_rect
			(start -0.508 0.9398)
			(end 0.508 -0.9398)
			(stroke
				(width 0)
				(type default)
			)
			(fill no)
			(layer "F.CrtYd")
		)
		(fp_rect
			(start -0.508 0.9398)
			(end 0.508 -0.9398)
			(stroke
				(width 0)
				(type default)
			)
			(fill no)
			(layer "F.Fab")
		)
		(pad "1" smd custom
			(at 0 -0.4445)
			(size 0.1397 0.1397)
			(layers "F.Cu" "F.Mask" "F.Paste")
			(net "P3V3_STBY_VREG")
			(options
				(clearance outline)
				(anchor circle)
			)
			(primitives
				(gr_poly
					(pts
						(arc
							(start -0.1778 -0.2794)
							(mid -0.249642 -0.249642)
							(end -0.2794 -0.1778)
						)
						(arc
							(start -0.2794 0.1778)
							(mid -0.249642 0.249642)
							(end -0.1778 0.2794)
						)
						(arc
							(start 0.1778 0.2794)
							(mid 0.249642 0.249642)
							(end 0.2794 0.1778)
						)
						(arc
							(start 0.2794 -0.1778)
							(mid 0.249642 -0.249642)
							(end 0.1778 -0.2794)
						)
					)
					(width 0)
					(fill yes)
				)
			)
		)
		(pad "2" smd custom
			(at 0 0.4445)
			(size 0.1397 0.1397)
			(layers "F.Cu" "F.Mask" "F.Paste")
			(net "P3V3_STBY_RF")
			(options
				(clearance outline)
				(anchor circle)
			)
			(primitives
				(gr_poly
					(pts
						(arc
							(start -0.1778 -0.2794)
							(mid -0.249642 -0.249642)
							(end -0.2794 -0.1778)
						)
						(arc
							(start -0.2794 0.1778)
							(mid -0.249642 0.249642)
							(end -0.1778 0.2794)
						)
						(arc
							(start 0.1778 0.2794)
							(mid 0.249642 0.249642)
							(end 0.2794 0.1778)
						)
						(arc
							(start 0.2794 -0.1778)
							(mid 0.249642 -0.249642)
							(end 0.1778 -0.2794)
						)
					)
					(width 0)
					(fill yes)
				)
			)
		)
	)
	(footprint ""
		(layer "F.Cu")
		(at 37.1348 -116.713 180)
		(property "Reference" "R281"
			(at 0 0 180)
			(layer "F.SilkS")
			(hide yes)
			(effects
				(font
					(size 1.27 1.27)
				)
			)
		)
		(property "Value" "0R2J-2-GP"
			(at 0.064008 -3.993896 180)
			(unlocked yes)
			(layer "F.Fab")
			(hide yes)
			(effects
				(font
					(size 1.016 1.016)
					(thickness 0.1524)
				)
			)
		)
		(property "Device Type" "R402H16"
			(at 0.064008 -5.517896 180)
			(unlocked yes)
			(layer "F.Fab")
			(hide yes)
			(effects
				(font
					(size 1.016 1.016)
					(thickness 0.1524)
				)
			)
		)
		(duplicate_pad_numbers_are_jumpers no)
		(fp_line
			(start 0.508 -0.9398)
			(end -0.508 -0.9398)
			(stroke
				(width 0.1524)
				(type default)
			)
			(layer "F.SilkS")
		)
		(fp_line
			(start -0.508 -0.9398)
			(end -0.508 0.9398)
			(stroke
				(width 0.1524)
				(type default)
			)
			(layer "F.SilkS")
		)
		(fp_rect
			(start -0.508 0.9398)
			(end 0.508 -0.9398)
			(stroke
				(width 0)
				(type default)
			)
			(fill no)
			(layer "F.CrtYd")
		)
		(fp_rect
			(start -0.508 0.9398)
			(end 0.508 -0.9398)
			(stroke
				(width 0)
				(type default)
			)
			(fill no)
			(layer "F.Fab")
		)
		(pad "1" smd custom
			(at 0 -0.4445 180)
			(size 0.1397 0.1397)
			(layers "F.Cu" "F.Mask" "F.Paste")
			(net "RMII_BMC_TX_EN")
			(options
				(clearance outline)
				(anchor circle)
			)
			(primitives
				(gr_poly
					(pts
						(arc
							(start -0.1778 -0.2794)
							(mid -0.249642 -0.249642)
							(end -0.2794 -0.1778)
						)
						(arc
							(start -0.2794 0.1778)
							(mid -0.249642 0.249642)
							(end -0.1778 0.2794)
						)
						(arc
							(start 0.1778 0.2794)
							(mid 0.249642 0.249642)
							(end 0.2794 0.1778)
						)
						(arc
							(start 0.2794 -0.1778)
							(mid 0.249642 -0.249642)
							(end 0.1778 -0.2794)
						)
					)
					(width 0)
					(fill yes)
				)
			)
		)
		(pad "2" smd custom
			(at 0 0.4445 180)
			(size 0.1397 0.1397)
			(layers "F.Cu" "F.Mask" "F.Paste")
			(net "RMII0_BMC_C_TX_EN")
			(options
				(clearance outline)
				(anchor circle)
			)
			(primitives
				(gr_poly
					(pts
						(arc
							(start -0.1778 -0.2794)
							(mid -0.249642 -0.249642)
							(end -0.2794 -0.1778)
						)
						(arc
							(start -0.2794 0.1778)
							(mid -0.249642 0.249642)
							(end -0.1778 0.2794)
						)
						(arc
							(start 0.1778 0.2794)
							(mid 0.249642 0.249642)
							(end 0.2794 0.1778)
						)
						(arc
							(start 0.2794 -0.1778)
							(mid 0.249642 -0.249642)
							(end 0.1778 -0.2794)
						)
					)
					(width 0)
					(fill yes)
				)
			)
		)
	)
)
